(kicad_pcb
	(version 20260206)
	(generator "pcbnew")
	(generator_version "10.0")
	(general
		(thickness 1.6)
		(legacy_teardrops no)
	)
	(paper "A4")
	(title_block
		(title "Bryce Canyon_F.DPB_16315-1-OCP.brd")
		(comment 1 "Bryce Canyon / footprint 944 of 2223 (PCIE1), pads 74-76 of 76")
	)
	(layers
		(0 "F.Cu" signal "TOP")
		(4 "In1.Cu" signal "L2GND")
		(6 "In2.Cu" signal "L3")
		(8 "In3.Cu" signal "L4GND")
		(10 "In4.Cu" signal "L5")
		(12 "In5.Cu" signal "L6VCC")
		(14 "In6.Cu" signal "L7VCC")
		(16 "In7.Cu" signal "L8")
		(18 "In8.Cu" signal "L9GND")
		(20 "In9.Cu" signal "L10")
		(22 "In10.Cu" signal "L11GND")
		(2 "B.Cu" signal "BOTTOM")
		(9 "F.Adhes" user "F.Adhesive")
		(11 "B.Adhes" user "B.Adhesive")
		(13 "F.Paste" user "Package Geometry/Pastemask Top")
		(15 "B.Paste" user "Package Geometry/Pastemask Bottom")
		(5 "F.SilkS" user "Ref Des/Silkscreen Top")
		(7 "B.SilkS" user "Ref Des/Silkscreen Bottom")
		(1 "F.Mask" user "Board Geometry/Soldermask Top")
		(3 "B.Mask" user "Board Geometry/Soldermask Bottom")
		(17 "Dwgs.User" user "User.Drawings")
		(19 "Cmts.User" user "User.Comments")
		(21 "Eco1.User" user "User.Eco1")
		(23 "Eco2.User" user "User.Eco2")
		(25 "Edge.Cuts" user "Board Geometry/Outline")
		(27 "Margin" user)
		(31 "F.CrtYd" user "Package Geometry/Place Bound Top")
		(29 "B.CrtYd" user "Package Geometry/Place Bound Bottom")
		(35 "F.Fab" user "Ref Des/Assembly Top")
		(33 "B.Fab" user "Ref Des/Assembly Bottom")
	)
	(footprint ""
		(layer "F.Cu")
		(at 287.83661 -263.702292 -90)
		(property "Reference" "PCIE1"
			(at 0 0 270)
			(layer "F.SilkS")
			(hide yes)
			(effects
				(font
					(size 1.27 1.27)
				)
			)
		)
		(property "Value" "AMP-CONN76-8R-5-GP"
			(at -8.9408 -15.1892 270)
			(unlocked yes)
			(layer "F.Fab")
			(hide yes)
			(effects
				(font
					(size 1.016 1.016)
					(thickness 0.1524)
				)
			)
		)
		(property "Device Type" "PREFIT-76P-165151H483"
			(at -8.9408 -16.7132 270)
			(unlocked yes)
			(layer "F.Fab")
			(hide yes)
			(effects
				(font
					(size 1.016 1.016)
					(thickness 0.1524)
				)
			)
		)
		(duplicate_pad_numbers_are_jumpers no)
		(pad "GND26" thru_hole circle
			(at 12.599924 3.50012 270)
			(size 0.762 0.762)
			(drill 0.359918)
			(layers "*.Cu" "*.Mask")
			(remove_unused_layers no)
			(net "GND")
			(clearance 0.1651)
			(thermal_gap 0.1651)
		)
		(pad "GND27" thru_hole circle
			(at 12.599924 7.100062 270)
			(size 0.762 0.762)
			(drill 0.359918)
			(layers "*.Cu" "*.Mask")
			(remove_unused_layers no)
			(net "GND")
			(clearance 0.1651)
			(thermal_gap 0.1651)
		)
		(pad "GND28" thru_hole circle
			(at 12.599924 10.700004 270)
			(size 0.762 0.762)
			(drill 0.359918)
			(layers "*.Cu" "*.Mask")
			(remove_unused_layers no)
			(net "GND")
			(clearance 0.1651)
			(thermal_gap 0.1651)
		)
	)
)
